(kicad_pcb
	(version 20260206)
	(generator "pcbnew")
	(generator_version "10.0")
	(general
		(thickness 1.6)
		(legacy_teardrops no)
	)
	(paper "A4")
	(title_block
		(title "peb — Lightning_PEB_BRD.brd")
		(comment 1 "Lightning (Wiwynn / Facebook NVMe JBOF) / footprints 997-1004 of 2563")
	)
	(layers
		(0 "F.Cu" signal "TOP")
		(4 "In1.Cu" signal "L2GND")
		(6 "In2.Cu" signal "L3")
		(8 "In3.Cu" signal "L4VCC")
		(10 "In4.Cu" signal "L5VCC")
		(12 "In5.Cu" signal "L6")
		(14 "In6.Cu" signal "L7GND")
		(2 "B.Cu" signal "BOTTOM")
		(9 "F.Adhes" user "F.Adhesive")
		(11 "B.Adhes" user "B.Adhesive")
		(13 "F.Paste" user "Package Geometry/Pastemask Top")
		(15 "B.Paste" user "Package Geometry/Pastemask Bottom")
		(5 "F.SilkS" user "Ref Des/Silkscreen Top")
		(7 "B.SilkS" user "Ref Des/Silkscreen Bottom")
		(1 "F.Mask" user "Board Geometry/Soldermask Top")
		(3 "B.Mask" user "Board Geometry/Soldermask Bottom")
		(17 "Dwgs.User" user "User.Drawings")
		(19 "Cmts.User" user "User.Comments")
		(21 "Eco1.User" user "User.Eco1")
		(23 "Eco2.User" user "User.Eco2")
		(25 "Edge.Cuts" user "Board Geometry/Outline")
		(27 "Margin" user)
		(31 "F.CrtYd" user "Package Geometry/Place Bound Top")
		(29 "B.CrtYd" user "Package Geometry/Place Bound Bottom")
		(35 "F.Fab" user "Ref Des/Assembly Top")
		(33 "B.Fab" user "Ref Des/Assembly Bottom")
	)
	(footprint ""
		(layer "F.Cu")
		(at 333.915512 -184.878218 180)
		(property "Reference" "R7999"
			(at 0 0 180)
			(layer "F.SilkS")
			(hide yes)
			(effects
				(font
					(size 1.27 1.27)
				)
			)
		)
		(property "Value" "0R2J-2-GP"
			(at 0.064008 -3.993896 180)
			(unlocked yes)
			(layer "F.Fab")
			(hide yes)
			(effects
				(font
					(size 1.016 1.016)
					(thickness 0.1524)
				)
			)
		)
		(property "Device Type" "R402H16"
			(at 0.064008 -5.517896 180)
			(unlocked yes)
			(layer "F.Fab")
			(hide yes)
			(effects
				(font
					(size 1.016 1.016)
					(thickness 0.1524)
				)
			)
		)
		(duplicate_pad_numbers_are_jumpers no)
		(fp_line
			(start 0.508 -0.9398)
			(end -0.508 -0.9398)
			(stroke
				(width 0.1524)
				(type default)
			)
			(layer "F.SilkS")
		)
		(fp_line
			(start -0.508 -0.9398)
			(end -0.508 0.9398)
			(stroke
				(width 0.1524)
				(type default)
			)
			(layer "F.SilkS")
		)
		(fp_rect
			(start -0.508 0.9398)
			(end 0.508 -0.9398)
			(stroke
				(width 0)
				(type default)
			)
			(fill no)
			(layer "F.CrtYd")
		)
		(fp_rect
			(start -0.508 0.9398)
			(end 0.508 -0.9398)
			(stroke
				(width 0)
				(type default)
			)
			(fill no)
			(layer "F.Fab")
		)
		(pad "1" smd custom
			(at 0 -0.4445 180)
			(size 0.1397 0.1397)
			(layers "F.Cu" "F.Mask" "F.Paste")
			(net "BMC_PERST#15")
			(options
				(clearance outline)
				(anchor circle)
			)
			(primitives
				(gr_poly
					(pts
						(arc
							(start -0.1778 -0.2794)
							(mid -0.249642 -0.249642)
							(end -0.2794 -0.1778)
						)
						(arc
							(start -0.2794 0.1778)
							(mid -0.249642 0.249642)
							(end -0.1778 0.2794)
						)
						(arc
							(start 0.1778 0.2794)
							(mid 0.249642 0.249642)
							(end 0.2794 0.1778)
						)
						(arc
							(start 0.2794 -0.1778)
							(mid 0.249642 -0.249642)
							(end 0.1778 -0.2794)
						)
					)
					(width 0)
					(fill yes)
				)
			)
		)
		(pad "2" smd custom
			(at 0 0.4445 180)
			(size 0.1397 0.1397)
			(layers "F.Cu" "F.Mask" "F.Paste")
			(net "BMC_PERST#_R")
			(options
				(clearance outline)
				(anchor circle)
			)
			(primitives
				(gr_poly
					(pts
						(arc
							(start -0.1778 -0.2794)
							(mid -0.249642 -0.249642)
							(end -0.2794 -0.1778)
						)
						(arc
							(start -0.2794 0.1778)
							(mid -0.249642 0.249642)
							(end -0.1778 0.2794)
						)
						(arc
							(start 0.1778 0.2794)
							(mid 0.249642 0.249642)
							(end 0.2794 0.1778)
						)
						(arc
							(start 0.2794 -0.1778)
							(mid 0.249642 -0.249642)
							(end 0.1778 -0.2794)
						)
					)
					(width 0)
					(fill yes)
				)
			)
		)
	)
	(footprint ""
		(layer "F.Cu")
		(at 64.7446 -111.4044 -90)
		(property "Reference" "R32"
			(at 0 0 270)
			(layer "F.SilkS")
			(hide yes)
			(effects
				(font
					(size 1.27 1.27)
				)
			)
		)
		(property "Value" "0R2J-2-GP"
			(at 0.064008 -3.993896 270)
			(unlocked yes)
			(layer "F.Fab")
			(hide yes)
			(effects
				(font
					(size 1.016 1.016)
					(thickness 0.1524)
				)
			)
		)
		(property "Device Type" "R402H16"
			(at 0.064008 -5.517896 270)
			(unlocked yes)
			(layer "F.Fab")
			(hide yes)
			(effects
				(font
					(size 1.016 1.016)
					(thickness 0.1524)
				)
			)
		)
		(duplicate_pad_numbers_are_jumpers no)
		(fp_line
			(start -0.508 -0.9398)
			(end -0.508 0.9398)
			(stroke
				(width 0.1524)
				(type default)
			)
			(layer "F.SilkS")
		)
		(fp_line
			(start 0.508 -0.9398)
			(end -0.508 -0.9398)
			(stroke
				(width 0.1524)
				(type default)
			)
			(layer "F.SilkS")
		)
		(fp_rect
			(start -0.508 0.9398)
			(end 0.508 -0.9398)
			(stroke
				(width 0)
				(type default)
			)
			(fill no)
			(layer "F.CrtYd")
		)
		(fp_rect
			(start -0.508 0.9398)
			(end 0.508 -0.9398)
			(stroke
				(width 0)
				(type default)
			)
			(fill no)
			(layer "F.Fab")
		)
		(pad "1" smd custom
			(at 0 -0.4445 270)
			(size 0.1397 0.1397)
			(layers "F.Cu" "F.Mask" "F.Paste")
			(net "BMC_I2C11_MINI5_SDA")
			(options
				(clearance outline)
				(anchor circle)
			)
			(primitives
				(gr_poly
					(pts
						(arc
							(start -0.1778 -0.2794)
							(mid -0.249642 -0.249642)
							(end -0.2794 -0.1778)
						)
						(arc
							(start -0.2794 0.1778)
							(mid -0.249642 0.249642)
							(end -0.1778 0.2794)
						)
						(arc
							(start 0.1778 0.2794)
							(mid 0.249642 0.249642)
							(end 0.2794 0.1778)
						)
						(arc
							(start 0.2794 -0.1778)
							(mid 0.249642 -0.249642)
							(end 0.1778 -0.2794)
						)
					)
					(width 0)
					(fill yes)
				)
			)
		)
		(pad "2" smd custom
			(at 0 0.4445 270)
			(size 0.1397 0.1397)
			(layers "F.Cu" "F.Mask" "F.Paste")
			(net "BMC_I2C11_MINI5_SDA_S")
			(options
				(clearance outline)
				(anchor circle)
			)
			(primitives
				(gr_poly
					(pts
						(arc
							(start -0.1778 -0.2794)
							(mid -0.249642 -0.249642)
							(end -0.2794 -0.1778)
						)
						(arc
							(start -0.2794 0.1778)
							(mid -0.249642 0.249642)
							(end -0.1778 0.2794)
						)
						(arc
							(start 0.1778 0.2794)
							(mid 0.249642 0.249642)
							(end 0.2794 0.1778)
						)
						(arc
							(start 0.2794 -0.1778)
							(mid 0.249642 -0.249642)
							(end 0.1778 -0.2794)
						)
					)
					(width 0)
					(fill yes)
				)
			)
		)
	)
	(footprint ""
		(layer "F.Cu")
		(at 29.395928 -68.28028 90)
		(property "Reference" "C285"
			(at 0 0 90)
			(layer "F.SilkS")
			(hide yes)
			(effects
				(font
					(size 1.27 1.27)
				)
			)
		)
		(property "Value" "SC2D2U16V3KX-GP-U"
			(at 0 -2.8194 90)
			(unlocked yes)
			(layer "F.Fab")
			(hide yes)
			(effects
				(font
					(size 1.016 1.016)
					(thickness 0.1524)
				)
			)
		)
		(property "Device Type" "C603H40"
			(at 0 -4.3434 90)
			(unlocked yes)
			(layer "F.Fab")
			(hide yes)
			(effects
				(font
					(size 1.016 1.016)
					(thickness 0.1524)
				)
			)
		)
		(duplicate_pad_numbers_are_jumpers no)
		(fp_line
			(start 0.508 0)
			(end -0.508 0)
			(stroke
				(width 0.2032)
				(type default)
			)
			(layer "F.SilkS")
		)
		(fp_rect
			(start -0.5842 1.3335)
			(end 0.5842 -1.3335)
			(stroke
				(width 0)
				(type default)
			)
			(fill no)
			(layer "F.CrtYd")
		)
		(fp_rect
			(start -0.5842 1.3335)
			(end 0.5842 -1.3335)
			(stroke
				(width 0)
				(type default)
			)
			(fill no)
			(layer "F.Fab")
		)
		(pad "1" smd custom
			(at 0 -0.762 90)
			(size 0.2159 0.2159)
			(layers "F.Cu" "F.Mask" "F.Paste")
			(net "P3V3_STBY")
			(options
				(clearance outline)
				(anchor circle)
			)
			(primitives
				(gr_poly
					(pts
						(arc
							(start -0.3302 -0.4318)
							(mid -0.402042 -0.402042)
							(end -0.4318 -0.3302)
						)
						(arc
							(start -0.4318 0.3302)
							(mid -0.402042 0.402042)
							(end -0.3302 0.4318)
						)
						(arc
							(start 0.3302 0.4318)
							(mid 0.402042 0.402042)
							(end 0.4318 0.3302)
						)
						(arc
							(start 0.4318 -0.3302)
							(mid 0.402042 -0.402042)
							(end 0.3302 -0.4318)
						)
					)
					(width 0)
					(fill yes)
				)
			)
		)
		(pad "2" smd custom
			(at 0 0.762 90)
			(size 0.2159 0.2159)
			(layers "F.Cu" "F.Mask" "F.Paste")
			(net "GND")
			(options
				(clearance outline)
				(anchor circle)
			)
			(primitives
				(gr_poly
					(pts
						(arc
							(start -0.3302 -0.4318)
							(mid -0.402042 -0.402042)
							(end -0.4318 -0.3302)
						)
						(arc
							(start -0.4318 0.3302)
							(mid -0.402042 0.402042)
							(end -0.3302 0.4318)
						)
						(arc
							(start 0.3302 0.4318)
							(mid 0.402042 0.402042)
							(end 0.4318 0.3302)
						)
						(arc
							(start 0.4318 -0.3302)
							(mid 0.402042 -0.402042)
							(end 0.3302 -0.4318)
						)
					)
					(width 0)
					(fill yes)
				)
			)
		)
	)
	(footprint ""
		(layer "F.Cu")
		(at 17.930114 -92.684346)
		(property "Reference" "R2939"
			(at 0 0 0)
			(layer "F.SilkS")
			(hide yes)
			(effects
				(font
					(size 1.27 1.27)
				)
			)
		)
		(property "Value" "470KR2F-1-GP"
			(at 0.064008 -3.993896 0)
			(unlocked yes)
			(layer "F.Fab")
			(hide yes)
			(effects
				(font
					(size 1.016 1.016)
					(thickness 0.1524)
				)
			)
		)
		(property "Device Type" "R402H16"
			(at 0.064008 -5.517896 0)
			(unlocked yes)
			(layer "F.Fab")
			(hide yes)
			(effects
				(font
					(size 1.016 1.016)
					(thickness 0.1524)
				)
			)
		)
		(duplicate_pad_numbers_are_jumpers no)
		(fp_line
			(start -0.508 -0.9398)
			(end -0.508 0.9398)
			(stroke
				(width 0.1524)
				(type default)
			)
			(layer "F.SilkS")
		)
		(fp_line
			(start 0.508 -0.9398)
			(end -0.508 -0.9398)
			(stroke
				(width 0.1524)
				(type default)
			)
			(layer "F.SilkS")
		)
		(fp_rect
			(start -0.508 0.9398)
			(end 0.508 -0.9398)
			(stroke
				(width 0)
				(type default)
			)
			(fill no)
			(layer "F.CrtYd")
		)
		(fp_rect
			(start -0.508 0.9398)
			(end 0.508 -0.9398)
			(stroke
				(width 0)
				(type default)
			)
			(fill no)
			(layer "F.Fab")
		)
		(pad "1" smd custom
			(at 0 -0.4445)
			(size 0.1397 0.1397)
			(layers "F.Cu" "F.Mask" "F.Paste")
			(net "BMC_TPM_RST")
			(options
				(clearance outline)
				(anchor circle)
			)
			(primitives
				(gr_poly
					(pts
						(arc
							(start -0.1778 -0.2794)
							(mid -0.249642 -0.249642)
							(end -0.2794 -0.1778)
						)
						(arc
							(start -0.2794 0.1778)
							(mid -0.249642 0.249642)
							(end -0.1778 0.2794)
						)
						(arc
							(start 0.1778 0.2794)
							(mid 0.249642 0.249642)
							(end 0.2794 0.1778)
						)
						(arc
							(start 0.2794 -0.1778)
							(mid 0.249642 -0.249642)
							(end 0.1778 -0.2794)
						)
					)
					(width 0)
					(fill yes)
				)
			)
		)
		(pad "2" smd custom
			(at 0 0.4445)
			(size 0.1397 0.1397)
			(layers "F.Cu" "F.Mask" "F.Paste")
			(net "GND")
			(options
				(clearance outline)
				(anchor circle)
			)
			(primitives
				(gr_poly
					(pts
						(arc
							(start -0.1778 -0.2794)
							(mid -0.249642 -0.249642)
							(end -0.2794 -0.1778)
						)
						(arc
							(start -0.2794 0.1778)
							(mid -0.249642 0.249642)
							(end -0.1778 0.2794)
						)
						(arc
							(start 0.1778 0.2794)
							(mid 0.249642 0.249642)
							(end 0.2794 0.1778)
						)
						(arc
							(start 0.2794 -0.1778)
							(mid 0.249642 -0.249642)
							(end 0.1778 -0.2794)
						)
					)
					(width 0)
					(fill yes)
				)
			)
		)
	)
	(footprint ""
		(layer "F.Cu")
		(at 40.33266 -116.4463 -90)
		(property "Reference" "TP292"
			(at 0 0 270)
			(layer "F.SilkS")
			(hide yes)
			(effects
				(font
					(size 1.27 1.27)
				)
			)
		)
		(property "Value" "TPAD28-2-GP"
			(at -0.0127 -1.6637 270)
			(unlocked yes)
			(layer "F.Fab")
			(hide yes)
			(effects
				(font
					(size 1.016 1.016)
					(thickness 0.1524)
				)
			)
		)
		(property "Device Type" "TPAD28"
			(at -0.0127 -3.1877 270)
			(unlocked yes)
			(layer "F.Fab")
			(hide yes)
			(effects
				(font
					(size 1.016 1.016)
					(thickness 0.1524)
				)
			)
		)
		(duplicate_pad_numbers_are_jumpers no)
		(fp_poly
			(pts
				(arc
					(start 0 -0.3556)
					(mid 0 0.3556)
					(end 0 -0.3556)
				)
			)
			(stroke
				(width 0)
				(type default)
			)
			(fill no)
			(layer "F.CrtYd")
		)
		(fp_poly
			(pts
				(arc
					(start 0 -0.6096)
					(mid 0 0.6096)
					(end 0 -0.6096)
				)
			)
			(stroke
				(width 0)
				(type default)
			)
			(fill no)
			(layer "F.Fab")
		)
		(pad "1" smd circle
			(at 0 0 270)
			(size 0.7112 0.7112)
			(layers "F.Cu" "F.Mask" "F.Paste")
			(net "TP_GPIOV3")
		)
	)
	(footprint ""
		(layer "F.Cu")
		(at 116.6368 -95.0722)
		(property "Reference" "C688"
			(at 0 0 0)
			(layer "F.SilkS")
			(hide yes)
			(effects
				(font
					(size 1.27 1.27)
				)
			)
		)
		(property "Value" "SCD1U16V2KX-3GP"
			(at 1.1811 -2.7051 0)
			(unlocked yes)
			(layer "F.Fab")
			(hide yes)
			(effects
				(font
					(size 1.016 1.016)
					(thickness 0.1524)
				)
			)
		)
		(property "Device Type" "C402H22"
			(at 1.1811 -4.2291 0)
			(unlocked yes)
			(layer "F.Fab")
			(hide yes)
			(effects
				(font
					(size 1.016 1.016)
					(thickness 0.1524)
				)
			)
		)
		(duplicate_pad_numbers_are_jumpers no)
		(fp_rect
			(start -0.4318 0.9525)
			(end 0.4318 -0.9525)
			(stroke
				(width 0)
				(type default)
			)
			(fill no)
			(layer "F.CrtYd")
		)
		(fp_rect
			(start -0.4318 0.9525)
			(end 0.4318 -0.9525)
			(stroke
				(width 0)
				(type default)
			)
			(fill no)
			(layer "F.Fab")
		)
		(pad "1" smd custom
			(at 0 -0.4445)
			(size 0.1524 0.1524)
			(layers "F.Cu" "F.Mask" "F.Paste")
			(net "P3V3_STBY")
			(options
				(clearance outline)
				(anchor circle)
			)
			(primitives
				(gr_poly
					(pts
						(arc
							(start 0.3048 -0.2032)
							(mid 0.275042 -0.275042)
							(end 0.2032 -0.3048)
						)
						(arc
							(start -0.2032 -0.3048)
							(mid -0.275042 -0.275042)
							(end -0.3048 -0.2032)
						)
						(arc
							(start -0.3048 0.2032)
							(mid -0.275042 0.275042)
							(end -0.2032 0.3048)
						)
						(arc
							(start 0.2032 0.3048)
							(mid 0.275042 0.275042)
							(end 0.3048 0.2032)
						)
					)
					(width 0)
					(fill yes)
				)
			)
		)
		(pad "2" smd custom
			(at 0 0.4445)
			(size 0.1524 0.1524)
			(layers "F.Cu" "F.Mask" "F.Paste")
			(net "GND")
			(options
				(clearance outline)
				(anchor circle)
			)
			(primitives
				(gr_poly
					(pts
						(arc
							(start 0.3048 -0.2032)
							(mid 0.275042 -0.275042)
							(end 0.2032 -0.3048)
						)
						(arc
							(start -0.2032 -0.3048)
							(mid -0.275042 -0.275042)
							(end -0.3048 -0.2032)
						)
						(arc
							(start -0.3048 0.2032)
							(mid -0.275042 0.275042)
							(end -0.2032 0.3048)
						)
						(arc
							(start 0.2032 0.3048)
							(mid 0.275042 0.275042)
							(end 0.3048 0.2032)
						)
					)
					(width 0)
					(fill yes)
				)
			)
		)
	)
	(footprint ""
		(layer "F.Cu")
		(at 25.6286 -184.8612 -90)
		(property "Reference" "R965"
			(at 0 0 270)
			(layer "F.SilkS")
			(hide yes)
			(effects
				(font
					(size 1.27 1.27)
				)
			)
		)
		(property "Value" "0R2J-2-GP"
			(at 0.064008 -3.993896 270)
			(unlocked yes)
			(layer "F.Fab")
			(hide yes)
			(effects
				(font
					(size 1.016 1.016)
					(thickness 0.1524)
				)
			)
		)
		(property "Device Type" "R402H16"
			(at 0.064008 -5.517896 270)
			(unlocked yes)
			(layer "F.Fab")
			(hide yes)
			(effects
				(font
					(size 1.016 1.016)
					(thickness 0.1524)
				)
			)
		)
		(duplicate_pad_numbers_are_jumpers no)
		(fp_line
			(start -0.508 -0.9398)
			(end -0.508 0.9398)
			(stroke
				(width 0.1524)
				(type default)
			)
			(layer "F.SilkS")
		)
		(fp_line
			(start 0.508 -0.9398)
			(end -0.508 -0.9398)
			(stroke
				(width 0.1524)
				(type default)
			)
			(layer "F.SilkS")
		)
		(fp_rect
			(start -0.508 0.9398)
			(end 0.508 -0.9398)
			(stroke
				(width 0)
				(type default)
			)
			(fill no)
			(layer "F.CrtYd")
		)
		(fp_rect
			(start -0.508 0.9398)
			(end 0.508 -0.9398)
			(stroke
				(width 0)
				(type default)
			)
			(fill no)
			(layer "F.Fab")
		)
		(pad "1" smd custom
			(at 0 -0.4445 270)
			(size 0.1397 0.1397)
			(layers "F.Cu" "F.Mask" "F.Paste")
			(net "BMC_I2C5_SDA_R")
			(options
				(clearance outline)
				(anchor circle)
			)
			(primitives
				(gr_poly
					(pts
						(arc
							(start -0.1778 -0.2794)
							(mid -0.249642 -0.249642)
							(end -0.2794 -0.1778)
						)
						(arc
							(start -0.2794 0.1778)
							(mid -0.249642 0.249642)
							(end -0.1778 0.2794)
						)
						(arc
							(start 0.1778 0.2794)
							(mid 0.249642 0.249642)
							(end 0.2794 0.1778)
						)
						(arc
							(start 0.2794 -0.1778)
							(mid 0.249642 -0.249642)
							(end 0.1778 -0.2794)
						)
					)
					(width 0)
					(fill yes)
				)
			)
		)
		(pad "2" smd custom
			(at 0 0.4445 270)
			(size 0.1397 0.1397)
			(layers "F.Cu" "F.Mask" "F.Paste")
			(net "BMC_I2C5_D_PEB_SDA")
			(options
				(clearance outline)
				(anchor circle)
			)
			(primitives
				(gr_poly
					(pts
						(arc
							(start -0.1778 -0.2794)
							(mid -0.249642 -0.249642)
							(end -0.2794 -0.1778)
						)
						(arc
							(start -0.2794 0.1778)
							(mid -0.249642 0.249642)
							(end -0.1778 0.2794)
						)
						(arc
							(start 0.1778 0.2794)
							(mid 0.249642 0.249642)
							(end 0.2794 0.1778)
						)
						(arc
							(start 0.2794 -0.1778)
							(mid 0.249642 -0.249642)
							(end 0.1778 -0.2794)
						)
					)
					(width 0)
					(fill yes)
				)
			)
		)
	)
	(footprint ""
		(layer "F.Cu")
		(at 146.74342 -33.52292)
		(property "Reference" "C391"
			(at 0 0 0)
			(layer "F.SilkS")
			(hide yes)
			(effects
				(font
					(size 1.27 1.27)
				)
			)
		)
		(property "Value" "SCD22U10V2KX-1GP"
			(at 1.1811 -2.7051 0)
			(unlocked yes)
			(layer "F.Fab")
			(hide yes)
			(effects
				(font
					(size 1.016 1.016)
					(thickness 0.1524)
				)
			)
		)
		(property "Device Type" "C402H22"
			(at 1.1811 -4.2291 0)
			(unlocked yes)
			(layer "F.Fab")
			(hide yes)
			(effects
				(font
					(size 1.016 1.016)
					(thickness 0.1524)
				)
			)
		)
		(duplicate_pad_numbers_are_jumpers no)
		(fp_rect
			(start -0.4318 0.9525)
			(end 0.4318 -0.9525)
			(stroke
				(width 0)
				(type default)
			)
			(fill no)
			(layer "F.CrtYd")
		)
		(fp_rect
			(start -0.4318 0.9525)
			(end 0.4318 -0.9525)
			(stroke
				(width 0)
				(type default)
			)
			(fill no)
			(layer "F.Fab")
		)
		(pad "1" smd custom
			(at 0 -0.4445)
			(size 0.1524 0.1524)
			(layers "F.Cu" "F.Mask" "F.Paste")
			(net "PCIE_TX_CAP_N85")
			(options
				(clearance outline)
				(anchor circle)
			)
			(primitives
				(gr_poly
					(pts
						(arc
							(start 0.3048 -0.2032)
							(mid 0.275042 -0.275042)
							(end 0.2032 -0.3048)
						)
						(arc
							(start -0.2032 -0.3048)
							(mid -0.275042 -0.275042)
							(end -0.3048 -0.2032)
						)
						(arc
							(start -0.3048 0.2032)
							(mid -0.275042 0.275042)
							(end -0.2032 0.3048)
						)
						(arc
							(start 0.2032 0.3048)
							(mid 0.275042 0.275042)
							(end 0.3048 0.2032)
						)
					)
					(width 0)
					(fill yes)
				)
			)
		)
		(pad "2" smd custom
			(at 0 0.4445)
			(size 0.1524 0.1524)
			(layers "F.Cu" "F.Mask" "F.Paste")
			(net "PCIE_TX_N85")
			(options
				(clearance outline)
				(anchor circle)
			)
			(primitives
				(gr_poly
					(pts
						(arc
							(start 0.3048 -0.2032)
							(mid 0.275042 -0.275042)
							(end 0.2032 -0.3048)
						)
						(arc
							(start -0.2032 -0.3048)
							(mid -0.275042 -0.275042)
							(end -0.3048 -0.2032)
						)
						(arc
							(start -0.3048 0.2032)
							(mid -0.275042 0.275042)
							(end -0.2032 0.3048)
						)
						(arc
							(start 0.2032 0.3048)
							(mid 0.275042 0.275042)
							(end 0.3048 0.2032)
						)
					)
					(width 0)
					(fill yes)
				)
			)
		)
	)
)
